(kicad_sch
	(version 20250114)
	(generator "eeschema")
	(generator_version "9.0")
	(paper "A3")
	(title_block
		(title "Thunderbolt to 10GbE adapter")
		(date "2026-04-23")
		(rev "1.1.0")
		(company "Antmicro Ltd")
		(comment 1 "www.antmicro.com")
	)
	(bus_alias "USB_3.0"
		(members "CC1" "CC2" "D_A_N" "D_A_P" "RX0_P" "RX0_N" "RX1_P" "RX1_N" "TX0_P"
			"TX0_N" "TX1_P" "TX1_N" "SBU1" "SBU2" "D_B_N" "D_B_P"
		)
	)
	(text "Inrush current \nlimit 3 A"
		(exclude_from_sim no)
		(at 284.48 110.49 0)
		(effects
			(font
				(size 1.27 1.27)
			)
		)
	)
	(text "USB-C Connector"
		(exclude_from_sim no)
		(at 185.42 104.14 0)
		(effects
			(font
				(size 2.54 2.54)
				(bold yes)
			)
			(justify left bottom)
		)
	)
	(junction
		(at 242.57 99.06)
		(diameter 0)
		(color 0 0 0 0)
	)
	(junction
		(at 327.66 99.06)
		(diameter 0)
		(color 0 0 0 0)
	)
	(junction
		(at 308.61 99.06)
		(diameter 0)
		(color 0 0 0 0)
	)
	(junction
		(at 223.52 99.06)
		(diameter 0)
		(color 0 0 0 0)
	)
	(junction
		(at 276.86 99.06)
		(diameter 0)
		(color 0 0 0 0)
	)
	(junction
		(at 318.77 99.06)
		(diameter 0)
		(color 0 0 0 0)
	)
	(junction
		(at 295.91 109.22)
		(diameter 0)
		(color 0 0 0 0)
	)
	(junction
		(at 269.24 99.06)
		(diameter 0)
		(color 0 0 0 0)
	)
	(junction
		(at 209.55 185.42)
		(diameter 0)
		(color 0 0 0 0)
	)
	(junction
		(at 260.35 99.06)
		(diameter 0)
		(color 0 0 0 0)
	)
	(junction
		(at 227.33 99.06)
		(diameter 0)
		(color 0 0 0 0)
	)
	(junction
		(at 251.46 99.06)
		(diameter 0)
		(color 0 0 0 0)
	)
	(no_connect
		(at 279.4 101.6)
	)
	(bus_entry
		(at 232.41 168.91)
		(size -1.27 1.27)
		(stroke
			(width 0)
			(type default)
		)
	)
	(bus_entry
		(at 232.41 176.53)
		(size -1.27 1.27)
		(stroke
			(width 0)
			(type default)
		)
	)
	(bus_entry
		(at 232.41 143.51)
		(size -1.27 1.27)
		(stroke
			(width 0)
			(type default)
		)
	)
	(bus_entry
		(at 232.41 173.99)
		(size -1.27 1.27)
		(stroke
			(width 0)
			(type default)
		)
	)
	(bus_entry
		(at 232.41 130.81)
		(size -1.27 1.27)
		(stroke
			(width 0)
			(type default)
		)
	)
	(bus_entry
		(at 232.41 153.67)
		(size -1.27 1.27)
		(stroke
			(width 0)
			(type default)
		)
	)
	(bus_entry
		(at 232.41 125.73)
		(size -1.27 1.27)
		(stroke
			(width 0)
			(type default)
		)
	)
	(bus_entry
		(at 232.41 161.29)
		(size -1.27 1.27)
		(stroke
			(width 0)
			(type default)
		)
	)
	(bus_entry
		(at 232.41 123.19)
		(size -1.27 1.27)
		(stroke
			(width 0)
			(type default)
		)
	)
	(bus_entry
		(at 232.41 151.13)
		(size -1.27 1.27)
		(stroke
			(width 0)
			(type default)
		)
	)
	(bus_entry
		(at 232.41 133.35)
		(size -1.27 1.27)
		(stroke
			(width 0)
			(type default)
		)
	)
	(bus_entry
		(at 232.41 166.37)
		(size -1.27 1.27)
		(stroke
			(width 0)
			(type default)
		)
	)
	(bus_entry
		(at 232.41 158.75)
		(size -1.27 1.27)
		(stroke
			(width 0)
			(type default)
		)
	)
	(bus_entry
		(at 232.41 135.89)
		(size -1.27 1.27)
		(stroke
			(width 0)
			(type default)
		)
	)
	(bus_entry
		(at 232.41 138.43)
		(size -1.27 1.27)
		(stroke
			(width 0)
			(type default)
		)
	)
	(bus_entry
		(at 232.41 146.05)
		(size -1.27 1.27)
		(stroke
			(width 0)
			(type default)
		)
	)
	(bus
		(pts
			(xy 237.49 119.38) (xy 234.95 119.38)
		)
		(stroke
			(width 0)
			(type default)
		)
	)
	(wire
		(pts
			(xy 205.74 175.26) (xy 231.14 175.26)
		)
		(stroke
			(width 0)
			(type default)
		)
	)
	(wire
		(pts
			(xy 295.91 109.22) (xy 295.91 110.49)
		)
		(stroke
			(width 0)
			(type default)
		)
	)
	(wire
		(pts
			(xy 242.57 99.06) (xy 242.57 101.6)
		)
		(stroke
			(width 0)
			(type default)
		)
	)
	(wire
		(pts
			(xy 205.74 124.46) (xy 231.14 124.46)
		)
		(stroke
			(width 0)
			(type default)
		)
	)
	(wire
		(pts
			(xy 205.74 182.88) (xy 209.55 182.88)
		)
		(stroke
			(width 0)
			(type default)
		)
	)
	(wire
		(pts
			(xy 205.74 177.8) (xy 231.14 177.8)
		)
		(stroke
			(width 0)
			(type default)
		)
	)
	(wire
		(pts
			(xy 308.61 99.06) (xy 318.77 99.06)
		)
		(stroke
			(width 0)
			(type default)
		)
	)
	(bus
		(pts
			(xy 232.41 143.51) (xy 232.41 146.05)
		)
		(stroke
			(width 0)
			(type default)
		)
	)
	(wire
		(pts
			(xy 205.74 127) (xy 231.14 127)
		)
		(stroke
			(width 0)
			(type default)
		)
	)
	(wire
		(pts
			(xy 308.61 105.41) (xy 308.61 106.68)
		)
		(stroke
			(width 0)
			(type default)
		)
	)
	(bus
		(pts
			(xy 232.41 166.37) (xy 232.41 168.91)
		)
		(stroke
			(width 0)
			(type default)
		)
	)
	(wire
		(pts
			(xy 175.26 181.61) (xy 175.26 182.88)
		)
		(stroke
			(width 0)
			(type default)
		)
	)
	(wire
		(pts
			(xy 298.45 101.6) (xy 294.64 101.6)
		)
		(stroke
			(width 0)
			(type default)
		)
	)
	(wire
		(pts
			(xy 205.74 144.78) (xy 231.14 144.78)
		)
		(stroke
			(width 0)
			(type default)
		)
	)
	(wire
		(pts
			(xy 294.64 104.14) (xy 295.91 104.14)
		)
		(stroke
			(width 0)
			(type default)
		)
	)
	(wire
		(pts
			(xy 205.74 139.7) (xy 231.14 139.7)
		)
		(stroke
			(width 0)
			(type default)
		)
	)
	(wire
		(pts
			(xy 269.24 99.06) (xy 269.24 101.6)
		)
		(stroke
			(width 0)
			(type default)
		)
	)
	(wire
		(pts
			(xy 327.66 99.06) (xy 327.66 101.6)
		)
		(stroke
			(width 0)
			(type default)
		)
	)
	(wire
		(pts
			(xy 205.74 160.02) (xy 231.14 160.02)
		)
		(stroke
			(width 0)
			(type default)
		)
	)
	(bus
		(pts
			(xy 232.41 146.05) (xy 232.41 151.13)
		)
		(stroke
			(width 0)
			(type default)
		)
	)
	(wire
		(pts
			(xy 251.46 106.68) (xy 251.46 107.95)
		)
		(stroke
			(width 0)
			(type default)
		)
	)
	(wire
		(pts
			(xy 209.55 185.42) (xy 209.55 187.96)
		)
		(stroke
			(width 0)
			(type default)
		)
	)
	(wire
		(pts
			(xy 260.35 99.06) (xy 269.24 99.06)
		)
		(stroke
			(width 0)
			(type default)
		)
	)
	(bus
		(pts
			(xy 232.41 130.81) (xy 232.41 133.35)
		)
		(stroke
			(width 0)
			(type default)
		)
	)
	(bus
		(pts
			(xy 234.95 119.38) (xy 232.41 121.92)
		)
		(stroke
			(width 0)
			(type default)
		)
	)
	(wire
		(pts
			(xy 295.91 109.22) (xy 298.45 109.22)
		)
		(stroke
			(width 0)
			(type default)
		)
	)
	(wire
		(pts
			(xy 242.57 99.06) (xy 251.46 99.06)
		)
		(stroke
			(width 0)
			(type default)
		)
	)
	(wire
		(pts
			(xy 260.35 106.68) (xy 260.35 107.95)
		)
		(stroke
			(width 0)
			(type default)
		)
	)
	(wire
		(pts
			(xy 251.46 99.06) (xy 251.46 101.6)
		)
		(stroke
			(width 0)
			(type default)
		)
	)
	(wire
		(pts
			(xy 227.33 107.95) (xy 227.33 106.68)
		)
		(stroke
			(width 0)
			(type default)
		)
	)
	(wire
		(pts
			(xy 276.86 104.14) (xy 276.86 99.06)
		)
		(stroke
			(width 0)
			(type default)
		)
	)
	(wire
		(pts
			(xy 298.45 109.22) (xy 298.45 107.95)
		)
		(stroke
			(width 0)
			(type default)
		)
	)
	(wire
		(pts
			(xy 205.74 162.56) (xy 231.14 162.56)
		)
		(stroke
			(width 0)
			(type default)
		)
	)
	(bus
		(pts
			(xy 232.41 125.73) (xy 232.41 130.81)
		)
		(stroke
			(width 0)
			(type default)
		)
	)
	(wire
		(pts
			(xy 327.66 106.68) (xy 327.66 107.95)
		)
		(stroke
			(width 0)
			(type default)
		)
	)
	(wire
		(pts
			(xy 308.61 111.76) (xy 308.61 113.03)
		)
		(stroke
			(width 0)
			(type default)
		)
	)
	(wire
		(pts
			(xy 276.86 99.06) (xy 279.4 99.06)
		)
		(stroke
			(width 0)
			(type default)
		)
	)
	(bus
		(pts
			(xy 232.41 168.91) (xy 232.41 173.99)
		)
		(stroke
			(width 0)
			(type default)
		)
	)
	(bus
		(pts
			(xy 232.41 133.35) (xy 232.41 135.89)
		)
		(stroke
			(width 0)
			(type default)
		)
	)
	(wire
		(pts
			(xy 223.52 97.79) (xy 223.52 99.06)
		)
		(stroke
			(width 0)
			(type default)
		)
	)
	(wire
		(pts
			(xy 318.77 101.6) (xy 318.77 99.06)
		)
		(stroke
			(width 0)
			(type default)
		)
	)
	(wire
		(pts
			(xy 318.77 99.06) (xy 327.66 99.06)
		)
		(stroke
			(width 0)
			(type default)
		)
	)
	(bus
		(pts
			(xy 232.41 123.19) (xy 232.41 125.73)
		)
		(stroke
			(width 0)
			(type default)
		)
	)
	(wire
		(pts
			(xy 227.33 99.06) (xy 227.33 101.6)
		)
		(stroke
			(width 0)
			(type default)
		)
	)
	(wire
		(pts
			(xy 205.74 132.08) (xy 231.14 132.08)
		)
		(stroke
			(width 0)
			(type default)
		)
	)
	(wire
		(pts
			(xy 279.4 104.14) (xy 276.86 104.14)
		)
		(stroke
			(width 0)
			(type default)
		)
	)
	(bus
		(pts
			(xy 232.41 158.75) (xy 232.41 161.29)
		)
		(stroke
			(width 0)
			(type default)
		)
	)
	(wire
		(pts
			(xy 205.74 147.32) (xy 231.14 147.32)
		)
		(stroke
			(width 0)
			(type default)
		)
	)
	(wire
		(pts
			(xy 260.35 99.06) (xy 260.35 101.6)
		)
		(stroke
			(width 0)
			(type default)
		)
	)
	(wire
		(pts
			(xy 205.74 170.18) (xy 231.14 170.18)
		)
		(stroke
			(width 0)
			(type default)
		)
	)
	(bus
		(pts
			(xy 232.41 173.99) (xy 232.41 176.53)
		)
		(stroke
			(width 0)
			(type default)
		)
	)
	(wire
		(pts
			(xy 308.61 100.33) (xy 308.61 99.06)
		)
		(stroke
			(width 0)
			(type default)
		)
	)
	(wire
		(pts
			(xy 205.74 185.42) (xy 209.55 185.42)
		)
		(stroke
			(width 0)
			(type default)
		)
	)
	(wire
		(pts
			(xy 223.52 99.06) (xy 223.52 119.38)
		)
		(stroke
			(width 0)
			(type default)
		)
	)
	(wire
		(pts
			(xy 269.24 106.68) (xy 269.24 107.95)
		)
		(stroke
			(width 0)
			(type default)
		)
	)
	(bus
		(pts
			(xy 232.41 135.89) (xy 232.41 138.43)
		)
		(stroke
			(width 0)
			(type default)
		)
	)
	(bus
		(pts
			(xy 232.41 121.92) (xy 232.41 123.19)
		)
		(stroke
			(width 0)
			(type default)
		)
	)
	(wire
		(pts
			(xy 205.74 152.4) (xy 231.14 152.4)
		)
		(stroke
			(width 0)
			(type default)
		)
	)
	(bus
		(pts
			(xy 232.41 138.43) (xy 232.41 143.51)
		)
		(stroke
			(width 0)
			(type default)
		)
	)
	(wire
		(pts
			(xy 318.77 106.68) (xy 318.77 107.95)
		)
		(stroke
			(width 0)
			(type default)
		)
	)
	(wire
		(pts
			(xy 269.24 99.06) (xy 276.86 99.06)
		)
		(stroke
			(width 0)
			(type default)
		)
	)
	(wire
		(pts
			(xy 242.57 106.68) (xy 242.57 107.95)
		)
		(stroke
			(width 0)
			(type default)
		)
	)
	(wire
		(pts
			(xy 223.52 99.06) (xy 227.33 99.06)
		)
		(stroke
			(width 0)
			(type default)
		)
	)
	(wire
		(pts
			(xy 327.66 97.79) (xy 327.66 99.06)
		)
		(stroke
			(width 0)
			(type default)
		)
	)
	(wire
		(pts
			(xy 308.61 97.79) (xy 308.61 99.06)
		)
		(stroke
			(width 0)
			(type default)
		)
	)
	(bus
		(pts
			(xy 232.41 161.29) (xy 232.41 166.37)
		)
		(stroke
			(width 0)
			(type default)
		)
	)
	(wire
		(pts
			(xy 205.74 154.94) (xy 231.14 154.94)
		)
		(stroke
			(width 0)
			(type default)
		)
	)
	(wire
		(pts
			(xy 209.55 182.88) (xy 209.55 185.42)
		)
		(stroke
			(width 0)
			(type default)
		)
	)
	(wire
		(pts
			(xy 295.91 104.14) (xy 295.91 109.22)
		)
		(stroke
			(width 0)
			(type default)
		)
	)
	(bus
		(pts
			(xy 232.41 153.67) (xy 232.41 158.75)
		)
		(stroke
			(width 0)
			(type default)
		)
	)
	(wire
		(pts
			(xy 298.45 102.87) (xy 298.45 101.6)
		)
		(stroke
			(width 0)
			(type default)
		)
	)
	(wire
		(pts
			(xy 251.46 99.06) (xy 260.35 99.06)
		)
		(stroke
			(width 0)
			(type default)
		)
	)
	(wire
		(pts
			(xy 205.74 137.16) (xy 231.14 137.16)
		)
		(stroke
			(width 0)
			(type default)
		)
	)
	(wire
		(pts
			(xy 205.74 134.62) (xy 231.14 134.62)
		)
		(stroke
			(width 0)
			(type default)
		)
	)
	(bus
		(pts
			(xy 232.41 151.13) (xy 232.41 153.67)
		)
		(stroke
			(width 0)
			(type default)
		)
	)
	(wire
		(pts
			(xy 294.64 99.06) (xy 308.61 99.06)
		)
		(stroke
			(width 0)
			(type default)
		)
	)
	(wire
		(pts
			(xy 205.74 167.64) (xy 231.14 167.64)
		)
		(stroke
			(width 0)
			(type default)
		)
	)
	(wire
		(pts
			(xy 205.74 119.38) (xy 223.52 119.38)
		)
		(stroke
			(width 0)
			(type default)
		)
	)
	(wire
		(pts
			(xy 227.33 99.06) (xy 242.57 99.06)
		)
		(stroke
			(width 0)
			(type default)
		)
	)
	(label "VBUS"
		(at 255.27 99.06 0)
		(effects
			(font
				(size 1.27 1.27)
			)
			(justify left bottom)
		)
	)
	(label "USB3.D_B_N"
		(at 212.09 139.7 0)
		(effects
			(font
				(size 1.27 1.27)
			)
			(justify left bottom)
		)
	)
	(label "USB3.RX0_N"
		(at 212.09 147.32 0)
		(effects
			(font
				(size 1.27 1.27)
			)
			(justify left bottom)
		)
	)
	(label "USB3.RX0_P"
		(at 212.09 144.78 0)
		(effects
			(font
				(size 1.27 1.27)
			)
			(justify left bottom)
		)
	)
	(label "USB3.CC2"
		(at 212.09 127 0)
		(effects
			(font
				(size 1.27 1.27)
			)
			(justify left bottom)
		)
	)
	(label "USB3.D_A_P"
		(at 212.09 132.08 0)
		(effects
			(font
				(size 1.27 1.27)
			)
			(justify left bottom)
		)
	)
	(label "USB3.SBU1"
		(at 212.09 175.26 0)
		(effects
			(font
				(size 1.27 1.27)
			)
			(justify left bottom)
		)
	)
	(label "USB3.TX1_N"
		(at 212.09 170.18 0)
		(effects
			(font
				(size 1.27 1.27)
			)
			(justify left bottom)
		)
	)
	(label "USB3.TX1_P"
		(at 212.09 167.64 0)
		(effects
			(font
				(size 1.27 1.27)
			)
			(justify left bottom)
		)
	)
	(label "USB3.RX1_P"
		(at 212.09 160.02 0)
		(effects
			(font
				(size 1.27 1.27)
			)
			(justify left bottom)
		)
	)
	(label "USB3.D_B_P"
		(at 212.09 137.16 0)
		(effects
			(font
				(size 1.27 1.27)
			)
			(justify left bottom)
		)
	)
	(label "USB3.D_A_N"
		(at 212.09 134.62 0)
		(effects
			(font
				(size 1.27 1.27)
			)
			(justify left bottom)
		)
	)
	(label "USB3.TX0_N"
		(at 212.09 154.94 0)
		(effects
			(font
				(size 1.27 1.27)
			)
			(justify left bottom)
		)
	)
	(label "USB3.RX1_N"
		(at 212.09 162.56 0)
		(effects
			(font
				(size 1.27 1.27)
			)
			(justify left bottom)
		)
	)
	(label "USB3.TX0_P"
		(at 212.09 152.4 0)
		(effects
			(font
				(size 1.27 1.27)
			)
			(justify left bottom)
		)
	)
	(label "USB3.CC1"
		(at 212.09 124.46 0)
		(effects
			(font
				(size 1.27 1.27)
			)
			(justify left bottom)
		)
	)
	(label "USB3.SBU2"
		(at 212.09 177.8 0)
		(effects
			(font
				(size 1.27 1.27)
			)
			(justify left bottom)
		)
	)
	(hierarchical_label "USB3{USB_3.0}"
		(shape bidirectional)
		(at 237.49 119.38 0)
		(effects
			(font
				(size 1.27 1.27)
			)
			(justify left)
		)
	)
	(rule_area
		(polyline
			(pts
				(xy 205.74 128.27) (xy 228.6 128.27) (xy 228.6 142.24) (xy 205.74 142.24)
			)
			(stroke
				(width 0)
				(type dash)
			)
			(fill
				(type none)
			)
		)
	)
	(rule_area
		(polyline
			(pts
				(xy 228.6 142.24) (xy 205.74 142.24) (xy 205.74 172.72) (xy 228.6 172.72)
			)
			(stroke
				(width 0)
				(type dash)
			)
			(fill
				(type none)
			)
		)
	)
	(netclass_flag ""
		(length 2.54)
		(shape round)
		(at 228.6 129.54 270)
		(effects
			(font
				(size 1.27 1.27)
			)
			(justify right bottom)
		)
		(property "Netclass" "90Ohm-diff_USB2"
			(at 232.41 129.54 0)
			(effects
				(font
					(size 1.27 1.27)
				)
				(justify left)
			)
		)
		(property "Component Class" ""
			(at 452.12 182.88 0)
			(effects
				(font
					(size 1.27 1.27)
					(italic yes)
				)
				(justify right)
			)
		)
	)
	(netclass_flag ""
		(length 2.54)
		(shape round)
		(at 228.6 143.51 270)
		(effects
			(font
				(size 1.27 1.27)
			)
			(justify right bottom)
		)
		(property "Netclass" "85Ohm-diff_USB4"
			(at 232.41 143.51 0)
			(effects
				(font
					(size 1.27 1.27)
				)
				(justify left)
			)
		)
		(property "Component Class" ""
			(at 452.12 90.17 0)
			(effects
				(font
					(size 1.27 1.27)
					(italic yes)
				)
				(justify left)
			)
		)
	)
	(symbol
		(lib_id "antmicropower:GND")
		(at 251.46 107.95 0)
		(unit 1)
		(exclude_from_sim no)
		(in_bom yes)
		(on_board yes)
		(dnp no)
		(property "Reference" "#PWR07"
			(at 251.46 114.3 0)
			(effects
				(font
					(size 1.27 1.27)
				)
				(hide yes)
			)
		)
		(property "Value" "GND"
			(at 251.46 111.76 0)
			(effects
				(font
					(size 1.27 1.27)
				)
			)
		)
		(property "Footprint" ""
			(at 251.46 107.95 0)
			(effects
				(font
					(size 1.27 1.27)
				)
				(hide yes)
			)
		)
		(property "Datasheet" ""
			(at 251.46 107.95 0)
			(effects
				(font
					(size 1.27 1.27)
				)
				(hide yes)
			)
		)
		(property "Description" ""
			(at 251.46 107.95 0)
			(effects
				(font
					(size 1.27 1.27)
				)
				(hide yes)
			)
		)
		(property "Author" "Antmicro"
			(at 260.35 115.57 0)
			(effects
				(font
					(size 1.27 1.27)
					(thickness 0.15)
				)
				(justify left bottom)
				(hide yes)
			)
		)
		(property "License" "Apache-2.0"
			(at 260.35 118.11 0)
			(effects
				(font
					(size 1.27 1.27)
					(thickness 0.15)
				)
				(justify left bottom)
				(hide yes)
			)
		)
		(pin "1"
		)
		(instances
			(project "thunderbolt-to-10gbe-adapter"
				(path ""
					(reference "#PWR07")
					(unit 1)
				)
			)
		)
	)
	(symbol
		(lib_id "antmicropower:+5V")
		(at 327.66 97.79 0)
		(unit 1)
		(exclude_from_sim no)
		(in_bom yes)
		(on_board yes)
		(dnp no)
		(property "Reference" "#PWR013"
			(at 342.9 100.33 0)
			(effects
				(font
					(size 1.27 1.27)
					(thickness 0.15)
				)
				(justify left bottom)
				(hide yes)
			)
		)
		(property "Value" "+5V_USB"
			(at 327.66 93.98 0)
			(effects
				(font
					(size 1.27 1.27)
					(thickness 0.15)
				)
			)
		)
		(property "Footprint" ""
			(at 342.9 105.41 0)
			(effects
				(font
					(size 1.27 1.27)
					(thickness 0.15)
				)
				(justify left bottom)
				(hide yes)
			)
		)
		(property "Datasheet" ""
			(at 342.9 107.95 0)
			(effects
				(font
					(size 1.27 1.27)
					(thickness 0.15)
				)
				(justify left bottom)
				(hide yes)
			)
		)
		(property "Description" ""
			(at 342.9 110.49 0)
			(effects
				(font
					(size 1.27 1.27)
				)
				(justify left bottom)
				(hide yes)
			)
		)
		(property "Author" "Antmicro"
			(at 342.9 105.41 0)
			(effects
				(font
					(size 1.27 1.27)
					(thickness 0.15)
				)
				(justify left bottom)
				(hide yes)
			)
		)
		(property "License" "Apache-2.0"
			(at 342.9 107.95 0)
			(effects
				(font
					(size 1.27 1.27)
					(thickness 0.15)
				)
				(justify left bottom)
				(hide yes)
			)
		)
		(pin "1"
		)
		(instances
			(project "thunderbolt-to-10gbe-adapter"
				(path ""
					(reference "#PWR013")
					(unit 1)
				)
			)
		)
	)
	(symbol
		(lib_id "antmicropower:GND")
		(at 308.61 113.03 0)
		(unit 1)
		(exclude_from_sim no)
		(in_bom yes)
		(on_board yes)
		(dnp no)
		(property "Reference" "#PWR011"
			(at 308.61 119.38 0)
			(effects
				(font
					(size 1.27 1.27)
				)
				(justify left bottom)
				(hide yes)
			)
		)
		(property "Value" "GND"
			(at 308.61 116.84 0)
			(effects
				(font
					(size 1.27 1.27)
					(thickness 0.15)
				)
			)
		)
		(property "Footprint" ""
			(at 317.5 120.65 0)
			(effects
				(font
					(size 1.27 1.27)
					(thickness 0.15)
				)
				(justify left bottom)
				(hide yes)
			)
		)
		(property "Datasheet" ""
			(at 317.5 125.73 0)
			(effects
				(font
					(size 1.27 1.27)
					(thickness 0.15)
				)
				(justify left bottom)
				(hide yes)
			)
		)
		(property "Description" ""
			(at 308.61 113.03 0)
			(effects
				(font
					(size 1.27 1.27)
				)
				(hide yes)
			)
		)
		(property "Author" "Antmicro"
			(at 317.5 120.65 0)
			(effects
				(font
					(size 1.27 1.27)
					(thickness 0.15)
				)
				(justify left bottom)
				(hide yes)
			)
		)
		(property "License" "Apache-2.0"
			(at 317.5 123.19 0)
			(effects
				(font
					(size 1.27 1.27)
					(thickness 0.15)
				)
				(justify left bottom)
				(hide yes)
			)
		)
		(pin "1"
		)
		(instances
			(project "thunderbolt-to-10gbe-adapter"
				(path ""
					(reference "#PWR011")
					(unit 1)
				)
			)
		)
	)
	(symbol
		(lib_id "antmicropower:GND")
		(at 209.55 187.96 0)
		(unit 1)
		(exclude_from_sim no)
		(in_bom yes)
		(on_board yes)
		(dnp no)
		(property "Reference" "#PWR04"
			(at 209.55 194.31 0)
			(effects
				(font
					(size 1.27 1.27)
				)
				(hide yes)
			)
		)
		(property "Value" "GND"
			(at 209.55 191.77 0)
			(effects
				(font
					(size 1.27 1.27)
				)
			)
		)
		(property "Footprint" ""
			(at 209.55 187.96 0)
			(effects
				(font
					(size 1.27 1.27)
				)
				(hide yes)
			)
		)
		(property "Datasheet" ""
			(at 209.55 187.96 0)
			(effects
				(font
					(size 1.27 1.27)
				)
				(hide yes)
			)
		)
		(property "Description" ""
			(at 209.55 187.96 0)
			(effects
				(font
					(size 1.27 1.27)
				)
				(hide yes)
			)
		)
		(property "Author" "Antmicro"
			(at 218.44 195.58 0)
			(effects
				(font
					(size 1.27 1.27)
					(thickness 0.15)
				)
				(justify left bottom)
				(hide yes)
			)
		)
		(property "License" "Apache-2.0"
			(at 218.44 198.12 0)
			(effects
				(font
					(size 1.27 1.27)
					(thickness 0.15)
				)
				(justify left bottom)
				(hide yes)
			)
		)
		(pin "1"
		)
		(instances
			(project "thunderbolt-to-10gbe-adapter"
				(path ""
					(reference "#PWR04")
					(unit 1)
				)
			)
		)
	)
	(symbol
		(lib_id "antmicropower:PWR_FLAG")
		(at 308.61 97.79 0)
		(unit 1)
		(exclude_from_sim no)
		(in_bom yes)
		(on_board yes)
		(dnp no)
		(property "Reference" "#FLG03"
			(at 308.61 95.885 0)
			(effects
				(font
					(size 1.27 1.27)
				)
				(hide yes)
			)
		)
		(property "Value" "PWR_FLAG"
			(at 308.61 93.98 0)
			(effects
				(font
					(size 1.27 1.27)
				)
			)
		)
		(property "Footprint" ""
			(at 308.61 97.79 0)
			(effects
				(font
					(size 1.27 1.27)
				)
				(hide yes)
			)
		)
		(property "Datasheet" ""
			(at 308.61 97.79 0)
			(effects
				(font
					(size 1.27 1.27)
				)
				(hide yes)
			)
		)
		(property "Description" ""
			(at 308.61 100.33 0)
			(effects
				(font
					(size 1.27 1.27)
				)
				(justify left bottom)
				(hide yes)
			)
		)
		(pin "1"
		)
		(instances
			(project "thunderbolt-to-10gbe-adapter"
				(path ""
					(reference "#FLG03")
					(unit 1)
				)
			)
		)
	)
	(symbol
		(lib_id "antmicropower:PWR_FLAG")
		(at 223.52 97.79 0)
		(unit 1)
		(exclude_from_sim no)
		(in_bom yes)
		(on_board yes)
		(dnp no)
		(property "Reference" "#FLG02"
			(at 223.52 95.885 0)
			(effects
				(font
					(size 1.27 1.27)
				)
				(hide yes)
			)
		)
		(property "Value" "PWR_FLAG"
			(at 223.52 93.98 0)
			(effects
				(font
					(size 1.27 1.27)
				)
			)
		)
		(property "Footprint" ""
			(at 223.52 97.79 0)
			(effects
				(font
					(size 1.27 1.27)
				)
				(hide yes)
			)
		)
		(property "Datasheet" ""
			(at 223.52 97.79 0)
			(effects
				(font
					(size 1.27 1.27)
				)
				(hide yes)
			)
		)
		(property "Description" ""
			(at 223.52 100.33 0)
			(effects
				(font
					(size 1.27 1.27)
				)
				(justify left bottom)
				(hide yes)
			)
		)
		(pin "1"
		)
		(instances
			(project "thunderbolt-to-10gbe-adapter"
				(path ""
					(reference "#FLG02")
					(unit 1)
				)
			)
		)
	)
	(symbol
		(lib_id "antmicropower:GND")
		(at 327.66 107.95 0)
		(unit 1)
		(exclude_from_sim no)
		(in_bom yes)
		(on_board yes)
		(dnp no)
		(property "Reference" "#PWR014"
			(at 327.66 114.3 0)
			(effects
				(font
					(size 1.27 1.27)
				)
				(hide yes)
			)
		)
		(property "Value" "GND"
			(at 327.66 111.76 0)
			(effects
				(font
					(size 1.27 1.27)
				)
			)
		)
		(property "Footprint" ""
			(at 327.66 107.95 0)
			(effects
				(font
					(size 1.27 1.27)
				)
				(hide yes)
			)
		)
		(property "Datasheet" ""
			(at 327.66 107.95 0)
			(effects
				(font
					(size 1.27 1.27)
				)
				(hide yes)
			)
		)
		(property "Description" ""
			(at 327.66 107.95 0)
			(effects
				(font
					(size 1.27 1.27)
				)
				(hide yes)
			)
		)
		(property "Author" "Antmicro"
			(at 336.55 115.57 0)
			(effects
				(font
					(size 1.27 1.27)
					(thickness 0.15)
				)
				(justify left bottom)
				(hide yes)
			)
		)
		(property "License" "Apache-2.0"
			(at 336.55 118.11 0)
			(effects
				(font
					(size 1.27 1.27)
					(thickness 0.15)
				)
				(justify left bottom)
				(hide yes)
			)
		)
		(pin "1"
		)
		(instances
			(project "thunderbolt-to-10gbe-adapter"
				(path ""
					(reference "#PWR014")
					(unit 1)
				)
			)
		)
	)
	(symbol
		(lib_id "antmicroCapacitors0402:C_4u7_25V_0402")
		(at 318.77 106.68 90)
		(unit 1)
		(exclude_from_sim no)
		(in_bom yes)
		(on_board yes)
		(dnp no)
		(fields_autoplaced yes)
		(property "Reference" "C5"
			(at 321.31 102.8636 90)
			(effects
				(font
					(size 1.27 1.27)
					(thickness 0.15)
				)
				(justify right)
			)
		)
		(property "Value" "C_4u7_25V_0402"
			(at 328.93 86.36 0)
			(effects
				(font
					(size 1.27 1.27)
					(thickness 0.15)
				)
				(justify left bottom)
				(hide yes)
			)
		)
		(property "Footprint" "antmicro-footprints:C_0402_1005Metric"
			(at 331.47 86.36 0)
			(effects
				(font
					(size 1.27 1.27)
					(thickness 0.15)
				)
				(justify left bottom)
				(hide yes)
			)
		)
		(property "Datasheet" "https://www.murata.com/products/productdetail?partno=GRM155C61E475ME15%23"
			(at 334.01 86.36 0)
			(effects
				(font
					(size 1.27 1.27)
					(thickness 0.15)
				)
				(justify left bottom)
				(hide yes)
			)
		)
		(property "Description" "SMD Multilayer Ceramic Capacitor"
			(at 351.79 86.36 0)
			(effects
				(font
					(size 1.27 1.27)
				)
				(justify left bottom)
				(hide yes)
			)
		)
		(property "MPN" "GRM155C61E475ME15J"
			(at 336.55 86.36 0)
			(effects
				(font
					(size 1.27 1.27)
					(thickness 0.15)
				)
				(justify left bottom)
				(hide yes)
			)
		)
		(property "Manufacturer" "Murata"
			(at 339.09 86.36 0)
			(effects
				(font
					(size 1.27 1.27)
					(thickness 0.15)
				)
				(justify left bottom)
				(hide yes)
			)
		)
		(property "License" "Apache-2.0"
			(at 341.63 86.36 0)
			(effects
				(font
					(size 1.27 1.27)
					(thickness 0.15)
				)
				(justify left bottom)
				(hide yes)
			)
		)
		(property "Author" "Antmicro"
			(at 344.17 86.36 0)
			(effects
				(font
					(size 1.27 1.27)
					(thickness 0.15)
				)
				(justify left bottom)
				(hide yes)
			)
		)
		(property "Val" "4u7"
			(at 321.31 105.4036 90)
			(effects
				(font
					(size 1.27 1.27)
					(thickness 0.15)
				)
				(justify right)
			)
		)
		(property "Voltage" "25V"
			(at 346.71 86.36 0)
			(effects
				(font
					(size 1.27 1.27)
				)
				(justify left bottom)
				(hide yes)
			)
		)
		(property "Dielectric" "X5S"
			(at 349.25 86.36 0)
			(effects
				(font
					(size 1.27 1.27)
				)
				(justify left bottom)
				(hide yes)
			)
		)
		(pin "2"
		)
		(pin "1"
		)
		(instances
			(project "thunderbolt-to-10gbe-adapter"
				(path ""
					(reference "C5")
					(unit 1)
				)
			)
		)
	)
	(symbol
		(lib_id "antmicroResistors0402:R_2k2_0402")
		(at 298.45 107.95 90)
		(unit 1)
		(exclude_from_sim no)
		(in_bom yes)
		(on_board yes)
		(dnp no)
		(property "Reference" "R1"
			(at 299.72 104.14 90)
			(effects
				(font
					(size 1.27 1.27)
					(thickness 0.15)
				)
				(justify right)
			)
		)
		(property "Value" "R_2k2_0402"
			(at 311.15 87.63 0)
			(effects
				(font
					(size 1.27 1.27)
					(thickness 0.15)
				)
				(justify left bottom)
				(hide yes)
			)
		)
		(property "Footprint" "antmicro-footprints:R_0402_1005Metric"
			(at 313.69 87.63 0)
			(effects
				(font
					(size 1.27 1.27)
					(thickness 0.15)
				)
				(justify left bottom)
				(hide yes)
			)
		)
		(property "Datasheet" "https://www.bourns.com/docs/product-datasheets/cr.pdf"
			(at 316.23 87.63 0)
			(effects
				(font
					(size 1.27 1.27)
					(thickness 0.15)
				)
				(justify left bottom)
				(hide yes)
			)
		)
		(property "Description" "SMD Chip Resistor, 2.2 kohm, ± 1%, 62.5 mW, 0402 [1005 Metric], Thick Film, General Purpose"
			(at 328.93 87.63 0)
			(effects
				(font
					(size 1.27 1.27)
				)
				(justify left bottom)
				(hide yes)
			)
		)
		(property "MPN" "CR0402-FX-2201GLF"
			(at 318.77 87.63 0)
			(effects
				(font
					(size 1.27 1.27)
					(thickness 0.15)
				)
				(justify left bottom)
				(hide yes)
			)
		)
		(property "Manufacturer" "Bourns"
			(at 321.31 87.63 0)
			(effects
				(font
					(size 1.27 1.27)
					(thickness 0.15)
				)
				(justify left bottom)
				(hide yes)
			)
		)
		(property "License" "Apache-2.0"
			(at 323.85 87.63 0)
			(effects
				(font
					(size 1.27 1.27)
					(thickness 0.15)
				)
				(justify left bottom)
				(hide yes)
			)
		)
		(property "Author" "Antmicro"
			(at 326.39 87.63 0)
			(effects
				(font
					(size 1.27 1.27)
					(thickness 0.15)
				)
				(justify left bottom)
				(hide yes)
			)
		)
		(property "Val" "2k2"
			(at 299.72 106.68 90)
			(effects
				(font
					(size 1.27 1.27)
					(thickness 0.15)
				)
				(justify right)
			)
		)
		(property "Tolerance" "1%"
			(at 308.61 87.63 0)
			(effects
				(font
					(size 1.27 1.27)
				)
				(justify left bottom)
				(hide yes)
			)
		)
		(pin "2"
		)
		(pin "1"
		)
		(instances
			(project "thunderbolt-to-10gbe-adapter"
				(path ""
					(reference "R1")
					(unit 1)
				)
			)
		)
	)
	(symbol
		(lib_id "antmicropower:GND")
		(at 295.91 110.49 0)
		(unit 1)
		(exclude_from_sim no)
		(in_bom yes)
		(on_board yes)
		(dnp no)
		(property "Reference" "#PWR010"
			(at 295.91 116.84 0)
			(effects
				(font
					(size 1.27 1.27)
				)
				(justify left bottom)
				(hide yes)
			)
		)
		(property "Value" "GND"
			(at 295.91 114.3 0)
			(effects
				(font
					(size 1.27 1.27)
					(thickness 0.15)
				)
			)
		)
		(property "Footprint" ""
			(at 304.8 118.11 0)
			(effects
				(font
					(size 1.27 1.27)
					(thickness 0.15)
				)
				(justify left bottom)
				(hide yes)
			)
		)
		(property "Datasheet" ""
			(at 304.8 123.19 0)
			(effects
				(font
					(size 1.27 1.27)
					(thickness 0.15)
				)
				(justify left bottom)
				(hide yes)
			)
		)
		(property "Description" ""
			(at 295.91 110.49 0)
			(effects
				(font
					(size 1.27 1.27)
				)
				(hide yes)
			)
		)
		(property "Author" "Antmicro"
			(at 304.8 118.11 0)
			(effects
				(font
					(size 1.27 1.27)
					(thickness 0.15)
				)
				(justify left bottom)
				(hide yes)
			)
		)
		(property "License" "Apache-2.0"
			(at 304.8 120.65 0)
			(effects
				(font
					(size 1.27 1.27)
					(thickness 0.15)
				)
				(justify left bottom)
				(hide yes)
			)
		)
		(pin "1"
		)
		(instances
			(project "thunderbolt-to-10gbe-adapter"
				(path ""
					(reference "#PWR010")
					(unit 1)
				)
			)
		)
	)
	(symbol
		(lib_id "antmicropower:PWR_FLAG")
		(at 175.26 181.61 0)
		(unit 1)
		(exclude_from_sim no)
		(in_bom yes)
		(on_board yes)
		(dnp no)
		(fields_autoplaced yes)
		(property "Reference" "#FLG01"
			(at 175.26 179.705 0)
			(effects
				(font
					(size 1.27 1.27)
				)
				(hide yes)
			)
		)
		(property "Value" "PWR_FLAG"
			(at 175.26 176.53 0)
			(effects
				(font
					(size 1.27 1.27)
				)
			)
		)
		(property "Footprint" ""
			(at 175.26 181.61 0)
			(effects
				(font
					(size 1.27 1.27)
				)
				(hide yes)
			)
		)
		(property "Datasheet" ""
			(at 175.26 181.61 0)
			(effects
				(font
					(size 1.27 1.27)
				)
				(hide yes)
			)
		)
		(property "Description" ""
			(at 175.26 181.61 0)
			(effects
				(font
					(size 1.27 1.27)
				)
				(hide yes)
			)
		)
		(pin "1"
		)
		(instances
			(project "thunderbolt-to-10gbe-adapter"
				(path ""
					(reference "#FLG01")
					(unit 1)
				)
			)
		)
	)
	(symbol
		(lib_id "antmicropower:GND")
		(at 318.77 107.95 0)
		(unit 1)
		(exclude_from_sim no)
		(in_bom yes)
		(on_board yes)
		(dnp no)
		(property "Reference" "#PWR012"
			(at 318.77 114.3 0)
			(effects
				(font
					(size 1.27 1.27)
				)
				(hide yes)
			)
		)
		(property "Value" "GND"
			(at 318.77 111.76 0)
			(effects
				(font
					(size 1.27 1.27)
				)
			)
		)
		(property "Footprint" ""
			(at 318.77 107.95 0)
			(effects
				(font
					(size 1.27 1.27)
				)
				(hide yes)
			)
		)
		(property "Datasheet" ""
			(at 318.77 107.95 0)
			(effects
				(font
					(size 1.27 1.27)
				)
				(hide yes)
			)
		)
		(property "Description" ""
			(at 318.77 107.95 0)
			(effects
				(font
					(size 1.27 1.27)
				)
				(hide yes)
			)
		)
		(property "Author" "Antmicro"
			(at 327.66 115.57 0)
			(effects
				(font
					(size 1.27 1.27)
					(thickness 0.15)
				)
				(justify left bottom)
				(hide yes)
			)
		)
		(property "License" "Apache-2.0"
			(at 327.66 118.11 0)
			(effects
				(font
					(size 1.27 1.27)
					(thickness 0.15)
				)
				(justify left bottom)
				(hide yes)
			)
		)
		(pin "1"
		)
		(instances
			(project "thunderbolt-to-10gbe-adapter"
				(path ""
					(reference "#PWR012")
					(unit 1)
				)
			)
		)
	)
	(symbol
		(lib_id "antmicroLEDIndicationDiscrete:LED_G_0603_LTST-C190GKT")
		(at 308.61 111.76 90)
		(unit 1)
		(exclude_from_sim no)
		(in_bom yes)
		(on_board yes)
		(dnp no)
		(property "Reference" "D2"
			(at 309.88 107.95 90)
			(effects
				(font
					(size 1.27 1.27)
				)
				(justify right)
			)
		)
		(property "Value" "LED_G_0603_LTST-C190GKT"
			(at 316.23 88.9 0)
			(effects
				(font
					(size 1.27 1.27)
					(thickness 0.15)
				)
				(justify left bottom)
				(hide yes)
			)
		)
		(property "Footprint" "antmicro-footprints:LED_0603_1608Metric_G"
			(at 318.77 88.9 0)
			(effects
				(font
					(size 1.27 1.27)
					(thickness 0.15)
				)
				(justify left bottom)
				(hide yes)
			)
		)
		(property "Datasheet" "https://media.digikey.com/pdf/Data%20Sheets/Lite-On%20PDFs/LTST-C190GKT.pdf"
			(at 321.31 88.9 0)
			(effects
				(font
					(size 1.27 1.27)
					(thickness 0.15)
				)
				(justify left bottom)
				(hide yes)
			)
		)
		(property "Description" "LED, Green, SMD, 0603, 20 mA, 2.1 V, 569 nm"
			(at 308.61 111.76 0)
			(effects
				(font
					(size 1.27 1.27)
				)
				(hide yes)
			)
		)
		(property "MPN" "LTST-C190GKT"
			(at 323.85 88.9 0)
			(effects
				(font
					(size 1.27 1.27)
					(thickness 0.15)
				)
				(justify left bottom)
				(hide yes)
			)
		)
		(property "Manufacturer" "Lite-On"
			(at 326.39 88.9 0)
			(effects
				(font
					(size 1.27 1.27)
					(thickness 0.15)
				)
				(justify left bottom)
				(hide yes)
			)
		)
		(property "Author" "Antmicro"
			(at 328.93 88.9 0)
			(effects
				(font
					(size 1.27 1.27)
					(thickness 0.15)
				)
				(justify left bottom)
				(hide yes)
			)
		)
		(property "License" "Apache-2.0"
			(at 331.47 88.9 0)
			(effects
				(font
					(size 1.27 1.27)
					(thickness 0.15)
				)
				(justify left bottom)
				(hide yes)
			)
		)
		(property "Color" "Green"
			(at 309.88 110.49 90)
			(effects
				(font
					(size 1.27 1.27)
				)
				(justify right)
			)
		)
		(pin "1"
		)
		(pin "2"
		)
		(instances
			(project "thunderbolt-to-10gbe-adapter"
				(path ""
					(reference "D2")
					(unit 1)
				)
			)
		)
	)
	(symbol
		(lib_id "antmicropower:GND")
		(at 227.33 107.95 0)
		(unit 1)
		(exclude_from_sim no)
		(in_bom yes)
		(on_board yes)
		(dnp no)
		(property "Reference" "#PWR05"
			(at 227.33 114.3 0)
			(effects
				(font
					(size 1.27 1.27)
				)
				(justify left bottom)
				(hide yes)
			)
		)
		(property "Value" "GND"
			(at 227.33 111.76 0)
			(effects
				(font
					(size 1.27 1.27)
					(thickness 0.15)
				)
			)
		)
		(property "Footprint" ""
			(at 236.22 115.57 0)
			(effects
				(font
					(size 1.27 1.27)
					(thickness 0.15)
				)
				(justify left bottom)
				(hide yes)
			)
		)
		(property "Datasheet" ""
			(at 236.22 120.65 0)
			(effects
				(font
					(size 1.27 1.27)
					(thickness 0.15)
				)
				(justify left bottom)
				(hide yes)
			)
		)
		(property "Description" ""
			(at 227.33 107.95 0)
			(effects
				(font
					(size 1.27 1.27)
				)
				(hide yes)
			)
		)
		(property "Author" "Antmicro"
			(at 236.22 115.57 0)
			(effects
				(font
					(size 1.27 1.27)
					(thickness 0.15)
				)
				(justify left bottom)
				(hide yes)
			)
		)
		(property "License" "Apache-2.0"
			(at 236.22 118.11 0)
			(effects
				(font
					(size 1.27 1.27)
					(thickness 0.15)
				)
				(justify left bottom)
				(hide yes)
			)
		)
		(pin "1"
		)
		(instances
			(project "thunderbolt-to-10gbe-adapter"
				(path ""
					(reference "#PWR05")
					(unit 1)
				)
			)
		)
	)
	(symbol
		(lib_id "antmicroCapacitors0402:C_100n_0402")
		(at 251.46 106.68 90)
		(unit 1)
		(exclude_from_sim no)
		(in_bom yes)
		(on_board yes)
		(dnp no)
		(fields_autoplaced yes)
		(property "Reference" "C2"
			(at 254.635 102.8636 90)
			(effects
				(font
					(size 1.27 1.27)
					(thickness 0.15)
				)
				(justify right)
			)
		)
		(property "Value" "C_100n_0402"
			(at 261.62 86.36 0)
			(effects
				(font
					(size 1.27 1.27)
					(thickness 0.15)
				)
				(justify left bottom)
				(hide yes)
			)
		)
		(property "Footprint" "antmicro-footprints:C_0402_1005Metric"
			(at 264.16 86.36 0)
			(effects
				(font
					(size 1.27 1.27)
					(thickness 0.15)
				)
				(justify left bottom)
				(hide yes)
			)
		)
		(property "Datasheet" "https://www.murata.com/products/productdetail?partno=GRM155R61H104KE14%23"
			(at 266.7 86.36 0)
			(effects
				(font
					(size 1.27 1.27)
					(thickness 0.15)
				)
				(justify left bottom)
				(hide yes)
			)
		)
		(property "Description" "SMD Multilayer Ceramic Capacitor, 0.1 µF, 50 V, 0402 [1005 Metric], ± 10%, X5R, GRM Series"
			(at 251.46 106.68 0)
			(effects
				(font
					(size 1.27 1.27)
				)
				(hide yes)
			)
		)
		(property "MPN" "GRM155R61H104KE14D"
			(at 269.24 86.36 0)
			(effects
				(font
					(size 1.27 1.27)
					(thickness 0.15)
				)
				(justify left bottom)
				(hide yes)
			)
		)
		(property "Manufacturer" "Murata"
			(at 271.78 86.36 0)
			(effects
				(font
					(size 1.27 1.27)
					(thickness 0.15)
				)
				(justify left bottom)
				(hide yes)
			)
		)
		(property "License" "Apache-2.0"
			(at 274.32 86.36 0)
			(effects
				(font
					(size 1.27 1.27)
					(thickness 0.15)
				)
				(justify left bottom)
				(hide yes)
			)
		)
		(property "Val" "100n"
			(at 254.635 105.4036 90)
			(effects
				(font
					(size 1.27 1.27)
					(thickness 0.15)
				)
				(justify right)
			)
		)
		(property "Voltage" "50V"
			(at 279.4 86.36 0)
			(effects
				(font
					(size 1.27 1.27)
				)
				(justify left bottom)
				(hide yes)
			)
		)
		(property "Dielectric" "X5R"
			(at 281.94 86.36 0)
			(effects
				(font
					(size 1.27 1.27)
				)
				(justify left bottom)
				(hide yes)
			)
		)
		(property "Author" "Antmicro"
			(at 276.86 86.36 0)
			(effects
				(font
					(size 1.27 1.27)
					(thickness 0.15)
				)
				(justify left bottom)
				(hide yes)
			)
		)
		(pin "1"
		)
		(pin "2"
		)
		(instances
			(project "thunderbolt-to-10gbe-adapter"
				(path ""
					(reference "C2")
					(unit 1)
				)
			)
		)
	)
	(symbol
		(lib_id "antmicropower:GND")
		(at 175.26 182.88 0)
		(unit 1)
		(exclude_from_sim no)
		(in_bom yes)
		(on_board yes)
		(dnp no)
		(property "Reference" "#PWR03"
			(at 175.26 189.23 0)
			(effects
				(font
					(size 1.27 1.27)
				)
				(hide yes)
			)
		)
		(property "Value" "GND"
			(at 175.26 186.69 0)
			(effects
				(font
					(size 1.27 1.27)
				)
			)
		)
		(property "Footprint" ""
			(at 175.26 182.88 0)
			(effects
				(font
					(size 1.27 1.27)
				)
				(hide yes)
			)
		)
		(property "Datasheet" ""
			(at 175.26 182.88 0)
			(effects
				(font
					(size 1.27 1.27)
				)
				(hide yes)
			)
		)
		(property "Description" ""
			(at 175.26 182.88 0)
			(effects
				(font
					(size 1.27 1.27)
				)
				(hide yes)
			)
		)
		(property "Author" "Antmicro"
			(at 184.15 190.5 0)
			(effects
				(font
					(size 1.27 1.27)
					(thickness 0.15)
				)
				(justify left bottom)
				(hide yes)
			)
		)
		(property "License" "Apache-2.0"
			(at 184.15 193.04 0)
			(effects
				(font
					(size 1.27 1.27)
					(thickness 0.15)
				)
				(justify left bottom)
				(hide yes)
			)
		)
		(pin "1"
		)
		(instances
			(project "thunderbolt-to-10gbe-adapter"
				(path ""
					(reference "#PWR03")
					(unit 1)
				)
			)
		)
	)
	(symbol
		(lib_id "antmicroUSBConnectors:USB-C_JAE_DX07S024JJ2")
		(at 205.74 119.38 0)
		(unit 1)
		(exclude_from_sim no)
		(in_bom yes)
		(on_board yes)
		(dnp no)
		(fields_autoplaced yes)
		(property "Reference" "J1"
			(at 192.405 111.76 0)
			(effects
				(font
					(size 1.27 1.27)
					(thickness 0.15)
				)
			)
		)
		(property "Value" "USB-C_JAE_DX07S024JJ2"
			(at 242.57 119.38 0)
			(effects
				(font
					(size 1.27 1.27)
					(thickness 0.15)
				)
				(justify left bottom)
				(hide yes)
			)
		)
		(property "Footprint" "antmicro-footprints:USB-C_Receptacle_JAE_DX07S024JJ2"
			(at 242.57 121.92 0)
			(effects
				(font
					(size 1.27 1.27)
					(thickness 0.15)
				)
				(justify left bottom)
				(hide yes)
			)
		)
		(property "Datasheet" "https://www.jae.com/en/connectors/series/detail/product/id=66508"
			(at 242.57 124.46 0)
			(effects
				(font
					(size 1.27 1.27)
					(thickness 0.15)
				)
				(justify left bottom)
				(hide yes)
			)
		)
		(property "Description" "USB-C (USB TYPE-C) USB 3.2 Gen 2 (USB 3.1 Gen 2, Superspeed + (USB 3.1)) Receptacle Connector 24 Position Surface Mount, Right Angle"
			(at 205.74 119.38 0)
			(effects
				(font
					(size 1.27 1.27)
				)
				(hide yes)
			)
		)
		(property "MPN" "DX07S024JJ2"
			(at 192.405 114.3 0)
			(effects
				(font
					(size 1.27 1.27)
					(thickness 0.15)
				)
			)
		)
		(property "Manufacturer" "JAE Electronics"
			(at 242.57 129.54 0)
			(effects
				(font
					(size 1.27 1.27)
					(thickness 0.15)
				)
				(justify left bottom)
				(hide yes)
			)
		)
		(property "Author" "Antmicro"
			(at 242.57 132.08 0)
			(effects
				(font
					(size 1.27 1.27)
					(thickness 0.15)
				)
				(justify left bottom)
				(hide yes)
			)
		)
		(property "License" "Apache-2.0"
			(at 242.57 134.62 0)
			(effects
				(font
					(size 1.27 1.27)
					(thickness 0.15)
				)
				(justify left bottom)
				(hide yes)
			)
		)
		(pin "A1"
		)
		(pin "A10"
		)
		(pin "A11"
		)
		(pin "A12"
		)
		(pin "A2"
		)
		(pin "A3"
		)
		(pin "A4"
		)
		(pin "A5"
		)
		(pin "A6"
		)
		(pin "A7"
		)
		(pin "A8"
		)
		(pin "A9"
		)
		(pin "B1"
		)
		(pin "B10"
		)
		(pin "B11"
		)
		(pin "B12"
		)
		(pin "B2"
		)
		(pin "B3"
		)
		(pin "B4"
		)
		(pin "B5"
		)
		(pin "B6"
		)
		(pin "B7"
		)
		(pin "B8"
		)
		(pin "B9"
		)
		(pin "SH"
		)
		(instances
			(project "thunderbolt-to-10gbe-adapter"
				(path ""
					(reference "J1")
					(unit 1)
				)
			)
		)
	)
	(symbol
		(lib_id "antmicropower:GND")
		(at 260.35 107.95 0)
		(unit 1)
		(exclude_from_sim no)
		(in_bom yes)
		(on_board yes)
		(dnp no)
		(property "Reference" "#PWR08"
			(at 260.35 114.3 0)
			(effects
				(font
					(size 1.27 1.27)
				)
				(hide yes)
			)
		)
		(property "Value" "GND"
			(at 260.35 111.76 0)
			(effects
				(font
					(size 1.27 1.27)
				)
			)
		)
		(property "Footprint" ""
			(at 260.35 107.95 0)
			(effects
				(font
					(size 1.27 1.27)
				)
				(hide yes)
			)
		)
		(property "Datasheet" ""
			(at 260.35 107.95 0)
			(effects
				(font
					(size 1.27 1.27)
				)
				(hide yes)
			)
		)
		(property "Description" ""
			(at 260.35 107.95 0)
			(effects
				(font
					(size 1.27 1.27)
				)
				(hide yes)
			)
		)
		(property "Author" "Antmicro"
			(at 269.24 115.57 0)
			(effects
				(font
					(size 1.27 1.27)
					(thickness 0.15)
				)
				(justify left bottom)
				(hide yes)
			)
		)
		(property "License" "Apache-2.0"
			(at 269.24 118.11 0)
			(effects
				(font
					(size 1.27 1.27)
					(thickness 0.15)
				)
				(justify left bottom)
				(hide yes)
			)
		)
		(pin "1"
		)
		(instances
			(project "thunderbolt-to-10gbe-adapter"
				(path ""
					(reference "#PWR08")
					(unit 1)
				)
			)
		)
	)
	(symbol
		(lib_id "antmicroCapacitorspol:C_Pol_330u_6.3V_KEMET-T520-B")
		(at 327.66 101.6 270)
		(unit 1)
		(exclude_from_sim no)
		(in_bom yes)
		(on_board yes)
		(dnp yes)
		(fields_autoplaced yes)
		(property "Reference" "C6"
			(at 330.2 102.3366 90)
			(effects
				(font
					(size 1.27 1.27)
					(thickness 0.15)
				)
				(justify left)
			)
		)
		(property "Value" "C_Pol_330u_6.3V_KEMET-T520-B"
			(at 325.12 115.57 0)
			(effects
				(font
					(size 1.27 1.27)
					(thickness 0.15)
				)
				(justify left bottom)
				(hide yes)
			)
		)
		(property "Footprint" "antmicro-footprints:C_Pol_EIA-B"
			(at 320.04 115.57 0)
			(effects
				(font
					(size 1.27 1.27)
					(thickness 0.15)
				)
				(justify left bottom)
				(hide yes)
			)
		)
		(property "Datasheet" "https://www.kemet.com/en/us/capacitors/product/T520B337M006ATE040.html"
			(at 317.5 115.57 0)
			(effects
				(font
					(size 1.27 1.27)
					(thickness 0.15)
				)
				(justify left bottom)
				(hide yes)
			)
		)
		(property "Description" "Tantalum Polymer Capacitor, KO-CAP®, 330 µF, ± 20%, 6.3 V, B, 0.04 ohm, 1411 [3528 Metric]"
			(at 327.66 101.6 0)
			(effects
				(font
					(size 1.27 1.27)
				)
				(hide yes)
			)
		)
		(property "Val" "330u"
			(at 330.2 104.8766 90)
			(effects
				(font
					(size 1.27 1.27)
					(thickness 0.15)
				)
				(justify left)
			)
		)
		(property "MPN" "T520B337M006ATE040"
			(at 314.96 115.57 0)
			(effects
				(font
					(size 1.27 1.27)
					(thickness 0.15)
				)
				(justify left bottom)
				(hide yes)
			)
		)
		(property "Manufacturer" "KEMET"
			(at 312.42 115.57 0)
			(effects
				(font
					(size 1.27 1.27)
					(thickness 0.15)
				)
				(justify left bottom)
				(hide yes)
			)
		)
		(property "License" "Apache-2.0"
			(at 309.88 115.57 0)
			(effects
				(font
					(size 1.27 1.27)
					(thickness 0.15)
				)
				(justify left bottom)
				(hide yes)
			)
		)
		(property "Author" "Antmicro"
			(at 307.34 115.57 0)
			(effects
				(font
					(size 1.27 1.27)
					(thickness 0.15)
				)
				(justify left bottom)
				(hide yes)
			)
		)
		(property "Voltage" "6.3V"
			(at 304.8 115.57 0)
			(effects
				(font
					(size 1.27 1.27)
				)
				(justify left bottom)
				(hide yes)
			)
		)
		(property "Dielectric" "template_dielectric"
			(at 302.26 115.57 0)
			(effects
				(font
					(size 1.27 1.27)
				)
				(justify left bottom)
				(hide yes)
			)
		)
		(pin "1"
		)
		(pin "2"
		)
		(instances
			(project "thunderbolt-to-10gbe-adapter"
				(path ""
					(reference "C6")
					(unit 1)
				)
			)
		)
	)
	(symbol
		(lib_id "antmicropower:GND")
		(at 269.24 107.95 0)
		(unit 1)
		(exclude_from_sim no)
		(in_bom yes)
		(on_board yes)
		(dnp no)
		(property "Reference" "#PWR09"
			(at 269.24 114.3 0)
			(effects
				(font
					(size 1.27 1.27)
				)
				(hide yes)
			)
		)
		(property "Value" "GND"
			(at 269.24 111.76 0)
			(effects
				(font
					(size 1.27 1.27)
				)
			)
		)
		(property "Footprint" ""
			(at 269.24 107.95 0)
			(effects
				(font
					(size 1.27 1.27)
				)
				(hide yes)
			)
		)
		(property "Datasheet" ""
			(at 269.24 107.95 0)
			(effects
				(font
					(size 1.27 1.27)
				)
				(hide yes)
			)
		)
		(property "Description" ""
			(at 269.24 107.95 0)
			(effects
				(font
					(size 1.27 1.27)
				)
				(hide yes)
			)
		)
		(property "Author" "Antmicro"
			(at 278.13 115.57 0)
			(effects
				(font
					(size 1.27 1.27)
					(thickness 0.15)
				)
				(justify left bottom)
				(hide yes)
			)
		)
		(property "License" "Apache-2.0"
			(at 278.13 118.11 0)
			(effects
				(font
					(size 1.27 1.27)
					(thickness 0.15)
				)
				(justify left bottom)
				(hide yes)
			)
		)
		(pin "1"
		)
		(instances
			(project "thunderbolt-to-10gbe-adapter"
				(path ""
					(reference "#PWR09")
					(unit 1)
				)
			)
		)
	)
	(symbol
		(lib_id "antmicroResistors0402:R_470R_0402")
		(at 308.61 105.41 90)
		(unit 1)
		(exclude_from_sim no)
		(in_bom yes)
		(on_board yes)
		(dnp no)
		(fields_autoplaced yes)
		(property "Reference" "R2"
			(at 311.15 101.6 90)
			(effects
				(font
					(size 1.27 1.27)
					(thickness 0.15)
				)
				(justify right)
			)
		)
		(property "Value" "R_470R_0402"
			(at 321.31 85.09 0)
			(effects
				(font
					(size 1.27 1.27)
					(thickness 0.15)
				)
				(justify left bottom)
				(hide yes)
			)
		)
		(property "Footprint" "antmicro-footprints:R_0402_1005Metric"
			(at 323.85 85.09 0)
			(effects
				(font
					(size 1.27 1.27)
					(thickness 0.15)
				)
				(justify left bottom)
				(hide yes)
			)
		)
		(property "Datasheet" "https://www.bourns.com/docs/product-datasheets/cr.pdf"
			(at 326.39 85.09 0)
			(effects
				(font
					(size 1.27 1.27)
					(thickness 0.15)
				)
				(justify left bottom)
				(hide yes)
			)
		)
		(property "Description" "SMD Chip Resistor, 470 ohm, ± 1%, 62.5 mW, 0402 [1005 Metric], Thick Film, General Purpose"
			(at 308.61 105.41 0)
			(effects
				(font
					(size 1.27 1.27)
				)
				(hide yes)
			)
		)
		(property "MPN" "CR0402-FX-4700GLF"
			(at 328.93 85.09 0)
			(effects
				(font
					(size 1.27 1.27)
					(thickness 0.15)
				)
				(justify left bottom)
				(hide yes)
			)
		)
		(property "Manufacturer" "Bourns"
			(at 331.47 85.09 0)
			(effects
				(font
					(size 1.27 1.27)
					(thickness 0.15)
				)
				(justify left bottom)
				(hide yes)
			)
		)
		(property "License" "Apache-2.0"
			(at 334.01 85.09 0)
			(effects
				(font
					(size 1.27 1.27)
					(thickness 0.15)
				)
				(justify left bottom)
				(hide yes)
			)
		)
		(property "Author" "Antmicro"
			(at 336.55 85.09 0)
			(effects
				(font
					(size 1.27 1.27)
					(thickness 0.15)
				)
				(justify left bottom)
				(hide yes)
			)
		)
		(property "Val" "470R"
			(at 311.15 104.14 90)
			(effects
				(font
					(size 1.27 1.27)
					(thickness 0.15)
				)
				(justify right)
			)
		)
		(property "Tolerance" "1%"
			(at 318.77 85.09 0)
			(effects
				(font
					(size 1.27 1.27)
				)
				(justify left bottom)
				(hide yes)
			)
		)
		(pin "2"
		)
		(pin "1"
		)
		(instances
			(project "thunderbolt-to-10gbe-adapter"
				(path ""
					(reference "R2")
					(unit 1)
				)
			)
		)
	)
	(symbol
		(lib_id "antmicroPMICPowerDistributionSwitchesLoadDrivers:AP22615A_TSOT26")
		(at 279.4 99.06 0)
		(unit 1)
		(exclude_from_sim no)
		(in_bom yes)
		(on_board yes)
		(dnp no)
		(fields_autoplaced yes)
		(property "Reference" "U1"
			(at 287.02 91.44 0)
			(effects
				(font
					(size 1.27 1.27)
					(thickness 0.15)
				)
			)
		)
		(property "Value" "AP22615A_TSOT26"
			(at 309.88 104.14 0)
			(effects
				(font
					(size 1.27 1.27)
					(thickness 0.15)
				)
				(justify left bottom)
				(hide yes)
			)
		)
		(property "Footprint" "antmicro-footprints:TSOT23-6"
			(at 309.88 106.68 0)
			(effects
				(font
					(size 1.27 1.27)
					(thickness 0.15)
				)
				(justify left bottom)
				(hide yes)
			)
		)
		(property "Datasheet" "https://www.mouser.com/datasheet/2/115/DIOD_S_A0008958405_1-2543193.pdf"
			(at 309.88 109.22 0)
			(effects
				(font
					(size 1.27 1.27)
					(thickness 0.15)
				)
				(justify left bottom)
				(hide yes)
			)
		)
		(property "Description" "Power Load Distribution Switch, High Side, Active High, 1 Output, 5.5 V, 3.6 A, 0.04 ohm, TSOT-26-6"
			(at 309.88 121.92 0)
			(effects
				(font
					(size 1.27 1.27)
				)
				(justify left bottom)
				(hide yes)
			)
		)
		(property "MPN" "AP22615AWU-7"
			(at 287.02 93.98 0)
			(effects
				(font
					(size 1.27 1.27)
					(thickness 0.15)
				)
			)
		)
		(property "Manufacturer" "Diodes Incorporated"
			(at 309.88 114.3 0)
			(effects
				(font
					(size 1.27 1.27)
					(thickness 0.15)
				)
				(justify left bottom)
				(hide yes)
			)
		)
		(property "Author" "Antmicro"
			(at 309.88 116.84 0)
			(effects
				(font
					(size 1.27 1.27)
					(thickness 0.15)
				)
				(justify left bottom)
				(hide yes)
			)
		)
		(property "License" "Apache-2.0"
			(at 309.88 119.38 0)
			(effects
				(font
					(size 1.27 1.27)
					(thickness 0.15)
				)
				(justify left bottom)
				(hide yes)
			)
		)
		(pin "6"
		)
		(pin "2"
		)
		(pin "1"
		)
		(pin "4"
		)
		(pin "5"
		)
		(pin "3"
		)
		(instances
			(project "thunderbolt-to-10gbe-adapter"
				(path ""
					(reference "U1")
					(unit 1)
				)
			)
		)
	)
	(symbol
		(lib_id "antmicropower:GND")
		(at 242.57 107.95 0)
		(unit 1)
		(exclude_from_sim no)
		(in_bom yes)
		(on_board yes)
		(dnp no)
		(property "Reference" "#PWR06"
			(at 242.57 114.3 0)
			(effects
				(font
					(size 1.27 1.27)
				)
				(hide yes)
			)
		)
		(property "Value" "GND"
			(at 242.57 111.76 0)
			(effects
				(font
					(size 1.27 1.27)
				)
			)
		)
		(property "Footprint" ""
			(at 242.57 107.95 0)
			(effects
				(font
					(size 1.27 1.27)
				)
				(hide yes)
			)
		)
		(property "Datasheet" ""
			(at 242.57 107.95 0)
			(effects
				(font
					(size 1.27 1.27)
				)
				(hide yes)
			)
		)
		(property "Description" ""
			(at 242.57 107.95 0)
			(effects
				(font
					(size 1.27 1.27)
				)
				(hide yes)
			)
		)
		(property "Author" "Antmicro"
			(at 251.46 115.57 0)
			(effects
				(font
					(size 1.27 1.27)
					(thickness 0.15)
				)
				(justify left bottom)
				(hide yes)
			)
		)
		(property "License" "Apache-2.0"
			(at 251.46 118.11 0)
			(effects
				(font
					(size 1.27 1.27)
					(thickness 0.15)
				)
				(justify left bottom)
				(hide yes)
			)
		)
		(pin "1"
		)
		(instances
			(project "thunderbolt-to-10gbe-adapter"
				(path ""
					(reference "#PWR06")
					(unit 1)
				)
			)
		)
	)
	(symbol
		(lib_id "antmicroCapacitors0402:C_100n_0402")
		(at 242.57 106.68 90)
		(unit 1)
		(exclude_from_sim no)
		(in_bom yes)
		(on_board yes)
		(dnp no)
		(fields_autoplaced yes)
		(property "Reference" "C1"
			(at 245.11 102.8636 90)
			(effects
				(font
					(size 1.27 1.27)
					(thickness 0.15)
				)
				(justify right)
			)
		)
		(property "Value" "C_100n_0402"
			(at 252.73 86.36 0)
			(effects
				(font
					(size 1.27 1.27)
					(thickness 0.15)
				)
				(justify left bottom)
				(hide yes)
			)
		)
		(property "Footprint" "antmicro-footprints:C_0402_1005Metric"
			(at 255.27 86.36 0)
			(effects
				(font
					(size 1.27 1.27)
					(thickness 0.15)
				)
				(justify left bottom)
				(hide yes)
			)
		)
		(property "Datasheet" "https://www.murata.com/products/productdetail?partno=GRM155R61H104KE14%23"
			(at 257.81 86.36 0)
			(effects
				(font
					(size 1.27 1.27)
					(thickness 0.15)
				)
				(justify left bottom)
				(hide yes)
			)
		)
		(property "Description" "SMD Multilayer Ceramic Capacitor, 0.1 µF, 50 V, 0402 [1005 Metric], ± 10%, X5R, GRM Series"
			(at 242.57 106.68 0)
			(effects
				(font
					(size 1.27 1.27)
				)
				(hide yes)
			)
		)
		(property "MPN" "GRM155R61H104KE14D"
			(at 260.35 86.36 0)
			(effects
				(font
					(size 1.27 1.27)
					(thickness 0.15)
				)
				(justify left bottom)
				(hide yes)
			)
		)
		(property "Manufacturer" "Murata"
			(at 262.89 86.36 0)
			(effects
				(font
					(size 1.27 1.27)
					(thickness 0.15)
				)
				(justify left bottom)
				(hide yes)
			)
		)
		(property "License" "Apache-2.0"
			(at 265.43 86.36 0)
			(effects
				(font
					(size 1.27 1.27)
					(thickness 0.15)
				)
				(justify left bottom)
				(hide yes)
			)
		)
		(property "Author" "Antmicro"
			(at 267.97 86.36 0)
			(effects
				(font
					(size 1.27 1.27)
					(thickness 0.15)
				)
				(justify left bottom)
				(hide yes)
			)
		)
		(property "Val" "100n"
			(at 245.11 105.4036 90)
			(effects
				(font
					(size 1.27 1.27)
					(thickness 0.15)
				)
				(justify right)
			)
		)
		(property "Voltage" "50V"
			(at 270.51 86.36 0)
			(effects
				(font
					(size 1.27 1.27)
				)
				(justify left bottom)
				(hide yes)
			)
		)
		(property "Dielectric" "X5R"
			(at 273.05 86.36 0)
			(effects
				(font
					(size 1.27 1.27)
				)
				(justify left bottom)
				(hide yes)
			)
		)
		(pin "1"
		)
		(pin "2"
		)
		(instances
			(project "thunderbolt-to-10gbe-adapter"
				(path ""
					(reference "C1")
					(unit 1)
				)
			)
		)
	)
	(symbol
		(lib_id "antmicroCapacitors0402:C_100n_0402")
		(at 269.24 106.68 90)
		(unit 1)
		(exclude_from_sim no)
		(in_bom yes)
		(on_board yes)
		(dnp no)
		(fields_autoplaced yes)
		(property "Reference" "C4"
			(at 271.78 102.8636 90)
			(effects
				(font
					(size 1.27 1.27)
					(thickness 0.15)
				)
				(justify right)
			)
		)
		(property "Value" "C_100n_0402"
			(at 279.4 86.36 0)
			(effects
				(font
					(size 1.27 1.27)
					(thickness 0.15)
				)
				(justify left bottom)
				(hide yes)
			)
		)
		(property "Footprint" "antmicro-footprints:C_0402_1005Metric"
			(at 281.94 86.36 0)
			(effects
				(font
					(size 1.27 1.27)
					(thickness 0.15)
				)
				(justify left bottom)
				(hide yes)
			)
		)
		(property "Datasheet" "https://www.murata.com/products/productdetail?partno=GRM155R61H104KE14%23"
			(at 284.48 86.36 0)
			(effects
				(font
					(size 1.27 1.27)
					(thickness 0.15)
				)
				(justify left bottom)
				(hide yes)
			)
		)
		(property "Description" "SMD Multilayer Ceramic Capacitor, 0.1 µF, 50 V, 0402 [1005 Metric], ± 10%, X5R, GRM Series"
			(at 269.24 106.68 0)
			(effects
				(font
					(size 1.27 1.27)
				)
				(hide yes)
			)
		)
		(property "MPN" "GRM155R61H104KE14D"
			(at 287.02 86.36 0)
			(effects
				(font
					(size 1.27 1.27)
					(thickness 0.15)
				)
				(justify left bottom)
				(hide yes)
			)
		)
		(property "Manufacturer" "Murata"
			(at 289.56 86.36 0)
			(effects
				(font
					(size 1.27 1.27)
					(thickness 0.15)
				)
				(justify left bottom)
				(hide yes)
			)
		)
		(property "License" "Apache-2.0"
			(at 292.1 86.36 0)
			(effects
				(font
					(size 1.27 1.27)
					(thickness 0.15)
				)
				(justify left bottom)
				(hide yes)
			)
		)
		(property "Val" "100n"
			(at 271.78 105.4036 90)
			(effects
				(font
					(size 1.27 1.27)
					(thickness 0.15)
				)
				(justify right)
			)
		)
		(property "Voltage" "50V"
			(at 297.18 86.36 0)
			(effects
				(font
					(size 1.27 1.27)
				)
				(justify left bottom)
				(hide yes)
			)
		)
		(property "Dielectric" "X5R"
			(at 299.72 86.36 0)
			(effects
				(font
					(size 1.27 1.27)
				)
				(justify left bottom)
				(hide yes)
			)
		)
		(property "Author" "Antmicro"
			(at 294.64 86.36 0)
			(effects
				(font
					(size 1.27 1.27)
					(thickness 0.15)
				)
				(justify left bottom)
				(hide yes)
			)
		)
		(pin "1"
		)
		(pin "2"
		)
		(instances
			(project "thunderbolt-to-10gbe-adapter"
				(path ""
					(reference "C4")
					(unit 1)
				)
			)
		)
	)
	(symbol
		(lib_id "antmicroTVSDiodes:PESD5Z5_0F")
		(at 227.33 101.6 270)
		(unit 1)
		(exclude_from_sim no)
		(in_bom yes)
		(on_board yes)
		(dnp no)
		(property "Reference" "D1"
			(at 228.854 103.124 90)
			(effects
				(font
					(size 1.27 1.27)
				)
				(justify left)
			)
		)
		(property "Value" "PESD5Z5.0F"
			(at 212.09 123.19 0)
			(effects
				(font
					(size 1.27 1.27)
					(thickness 0.15)
				)
				(justify left bottom)
				(hide yes)
			)
		)
		(property "Footprint" "antmicro-footprints:SOD-523"
			(at 222.25 116.84 0)
			(effects
				(font
					(size 1.27 1.27)
					(thickness 0.15)
				)
				(justify left bottom)
				(hide yes)
			)
		)
		(property "Datasheet" "https://assets.nexperia.com/documents/data-sheet/PESD5Z5_0.pdf"
			(at 219.71 116.84 0)
			(effects
				(font
					(size 1.27 1.27)
					(thickness 0.15)
				)
				(justify left bottom)
				(hide yes)
			)
		)
		(property "Description" "Unidirectional TVS, 30 kV,  SOD-523, 5 V, 89 pF"
			(at 207.01 116.84 0)
			(effects
				(font
					(size 1.27 1.27)
				)
				(justify left bottom)
				(hide yes)
			)
		)
		(property "Manufacturer" "Nexperia"
			(at 217.17 116.84 0)
			(effects
				(font
					(size 1.27 1.27)
					(thickness 0.15)
				)
				(justify left bottom)
				(hide yes)
			)
		)
		(property "MPN" "PESD5Z5.0F"
			(at 228.854 105.664 90)
			(effects
				(font
					(size 1.27 1.27)
					(thickness 0.15)
				)
				(justify left bottom)
			)
		)
		(property "Author" "Antmicro"
			(at 212.09 116.84 0)
			(effects
				(font
					(size 1.27 1.27)
					(thickness 0.15)
				)
				(justify left bottom)
				(hide yes)
			)
		)
		(property "License" "Apache-2.0"
			(at 209.55 116.84 0)
			(effects
				(font
					(size 1.27 1.27)
					(thickness 0.15)
				)
				(justify left bottom)
				(hide yes)
			)
		)
		(pin "1"
		)
		(pin "2"
		)
		(instances
			(project "thunderbolt-to-10gbe-adapter"
				(path ""
					(reference "D1")
					(unit 1)
				)
			)
		)
	)
	(symbol
		(lib_id "antmicroCapacitors0402:C_100n_0402")
		(at 260.35 106.68 90)
		(unit 1)
		(exclude_from_sim no)
		(in_bom yes)
		(on_board yes)
		(dnp no)
		(fields_autoplaced yes)
		(property "Reference" "C3"
			(at 263.525 102.8636 90)
			(effects
				(font
					(size 1.27 1.27)
					(thickness 0.15)
				)
				(justify right)
			)
		)
		(property "Value" "C_100n_0402"
			(at 270.51 86.36 0)
			(effects
				(font
					(size 1.27 1.27)
					(thickness 0.15)
				)
				(justify left bottom)
				(hide yes)
			)
		)
		(property "Footprint" "antmicro-footprints:C_0402_1005Metric"
			(at 273.05 86.36 0)
			(effects
				(font
					(size 1.27 1.27)
					(thickness 0.15)
				)
				(justify left bottom)
				(hide yes)
			)
		)
		(property "Datasheet" "https://www.murata.com/products/productdetail?partno=GRM155R61H104KE14%23"
			(at 275.59 86.36 0)
			(effects
				(font
					(size 1.27 1.27)
					(thickness 0.15)
				)
				(justify left bottom)
				(hide yes)
			)
		)
		(property "Description" "SMD Multilayer Ceramic Capacitor, 0.1 µF, 50 V, 0402 [1005 Metric], ± 10%, X5R, GRM Series"
			(at 260.35 106.68 0)
			(effects
				(font
					(size 1.27 1.27)
				)
				(hide yes)
			)
		)
		(property "MPN" "GRM155R61H104KE14D"
			(at 278.13 86.36 0)
			(effects
				(font
					(size 1.27 1.27)
					(thickness 0.15)
				)
				(justify left bottom)
				(hide yes)
			)
		)
		(property "Manufacturer" "Murata"
			(at 280.67 86.36 0)
			(effects
				(font
					(size 1.27 1.27)
					(thickness 0.15)
				)
				(justify left bottom)
				(hide yes)
			)
		)
		(property "License" "Apache-2.0"
			(at 283.21 86.36 0)
			(effects
				(font
					(size 1.27 1.27)
					(thickness 0.15)
				)
				(justify left bottom)
				(hide yes)
			)
		)
		(property "Val" "100n"
			(at 263.525 105.4036 90)
			(effects
				(font
					(size 1.27 1.27)
					(thickness 0.15)
				)
				(justify right)
			)
		)
		(property "Voltage" "50V"
			(at 288.29 86.36 0)
			(effects
				(font
					(size 1.27 1.27)
				)
				(justify left bottom)
				(hide yes)
			)
		)
		(property "Dielectric" "X5R"
			(at 290.83 86.36 0)
			(effects
				(font
					(size 1.27 1.27)
				)
				(justify left bottom)
				(hide yes)
			)
		)
		(property "Author" "Antmicro"
			(at 285.75 86.36 0)
			(effects
				(font
					(size 1.27 1.27)
					(thickness 0.15)
				)
				(justify left bottom)
				(hide yes)
			)
		)
		(pin "1"
		)
		(pin "2"
		)
		(instances
			(project "thunderbolt-to-10gbe-adapter"
				(path ""
					(reference "C3")
					(unit 1)
				)
			)
		)
	)
)
